(kicad_pcb
	(version 20260206)
	(generator "pcbnew")
	(generator_version "10.0")
	(general
		(thickness 1.6)
		(legacy_teardrops no)
	)
	(paper "A4")
	(title_block
		(title "v2-tray-backplane — ms_tbp_v2.brd")
		(comment 1 "Open CloudServer (Microsoft) / footprint 17 of 164 (J14), pads 122-162 of 162")
	)
	(layers
		(0 "F.Cu" signal "TOP")
		(4 "In1.Cu" signal "LYR2")
		(6 "In2.Cu" signal "LYR3")
		(8 "In3.Cu" signal "LYR4")
		(10 "In4.Cu" signal "LYR5")
		(12 "In5.Cu" signal "LYR6")
		(14 "In6.Cu" signal "LYR7")
		(2 "B.Cu" signal "BOTTOM")
		(9 "F.Adhes" user "F.Adhesive")
		(11 "B.Adhes" user "B.Adhesive")
		(13 "F.Paste" user "Package Geometry/Pastemask Top")
		(15 "B.Paste" user "Package Geometry/Pastemask Bottom")
		(5 "F.SilkS" user "Ref Des/Silkscreen Top")
		(7 "B.SilkS" user "Ref Des/Silkscreen Bottom")
		(1 "F.Mask" user "Board Geometry/Soldermask Top")
		(3 "B.Mask" user "Board Geometry/Soldermask Bottom")
		(17 "Dwgs.User" user "User.Drawings")
		(19 "Cmts.User" user "User.Comments")
		(21 "Eco1.User" user "User.Eco1")
		(23 "Eco2.User" user "User.Eco2")
		(25 "Edge.Cuts" user "Board Geometry/Outline")
		(27 "Margin" user)
		(31 "F.CrtYd" user "Package Geometry/Place Bound Top")
		(29 "B.CrtYd" user "Package Geometry/Place Bound Bottom")
		(35 "F.Fab" user "Ref Des/Assembly Top")
		(33 "B.Fab" user "Ref Des/Assembly Bottom")
	)
	(footprint ""
		(layer "F.Cu")
		(at -154.079999 30.959999 90)
		(property "Reference" "J14"
			(at 17.078899 0.028999 0)
			(unlocked yes)
			(layer "F.SilkS")
			(effects
				(font
					(size 0.762 0.5334)
					(thickness 0.1016)
				)
			)
		)
		(property "Value" ""
			(at 0 0 90)
			(layer "F.Fab")
			(effects
				(font
					(size 1.27 1.27)
				)
			)
		)
		(duplicate_pad_numbers_are_jumpers no)
		(pad "120" smd circle
			(at 5.715 4.445 90)
			(size 0.635 0.635)
			(layers "F.Cu" "F.Mask" "F.Paste")
			(net "GND")
		)
		(pad "121" smd circle
			(at 6.985 -4.445 90)
			(size 0.635 0.635)
			(layers "F.Cu" "F.Mask" "F.Paste")
			(net "PCIE_T2B_B2_RX_DN<0>")
		)
		(pad "122" smd circle
			(at 6.985 -3.175 90)
			(size 0.635 0.635)
			(layers "F.Cu" "F.Mask" "F.Paste")
			(net "GND")
		)
		(pad "123" smd circle
			(at 6.985 -1.905 90)
			(size 0.635 0.635)
			(layers "F.Cu" "F.Mask" "F.Paste")
			(net "PCIE_T2B_B2_RX_DN<8>")
		)
		(pad "124" smd circle
			(at 6.985 -0.635 90)
			(size 0.635 0.635)
			(layers "F.Cu" "F.Mask" "F.Paste")
			(net "GND")
		)
		(pad "125" smd circle
			(at 6.985 0.635 90)
			(size 0.635 0.635)
			(layers "F.Cu" "F.Mask" "F.Paste")
			(net "PCIE_B2T_B2_TX_DN<0>")
		)
		(pad "126" smd circle
			(at 6.985 1.905 90)
			(size 0.635 0.635)
			(layers "F.Cu" "F.Mask" "F.Paste")
			(net "GND")
		)
		(pad "127" smd circle
			(at 6.985 3.175 90)
			(size 0.635 0.635)
			(layers "F.Cu" "F.Mask" "F.Paste")
			(net "PCIE_B2T_B2_TX_DN<8>")
		)
		(pad "128" smd circle
			(at 6.985 4.445 90)
			(size 0.635 0.635)
			(layers "F.Cu" "F.Mask" "F.Paste")
			(net "GND")
		)
		(pad "129" smd circle
			(at 8.255 -4.445 90)
			(size 0.635 0.635)
			(layers "F.Cu" "F.Mask" "F.Paste")
			(net "GND")
		)
		(pad "130" smd circle
			(at 8.255 -3.175 90)
			(size 0.635 0.635)
			(layers "F.Cu" "F.Mask" "F.Paste")
			(net "CLK_100M_B2_P<0>")
		)
		(pad "131" smd circle
			(at 8.255 -1.905 90)
			(size 0.635 0.635)
			(layers "F.Cu" "F.Mask" "F.Paste")
			(net "GND")
		)
		(pad "132" smd circle
			(at 8.255 -0.635 90)
			(size 0.635 0.635)
			(layers "F.Cu" "F.Mask" "F.Paste")
			(net "CLK_100M_B2_P<1>")
		)
		(pad "133" smd circle
			(at 8.255 0.635 90)
			(size 0.635 0.635)
			(layers "F.Cu" "F.Mask" "F.Paste")
			(net "GND")
		)
		(pad "134" smd circle
			(at 8.255 1.905 90)
			(size 0.635 0.635)
			(layers "F.Cu" "F.Mask" "F.Paste")
			(net "CLK_100M_B2_P<2>")
		)
		(pad "135" smd circle
			(at 8.255 3.175 90)
			(size 0.635 0.635)
			(layers "F.Cu" "F.Mask" "F.Paste")
			(net "GND")
		)
		(pad "136" smd circle
			(at 8.255 4.445 90)
			(size 0.635 0.635)
			(layers "F.Cu" "F.Mask" "F.Paste")
			(net "CLK_100M_B2_P<3>")
		)
		(pad "137" smd circle
			(at 9.525 -4.445 90)
			(size 0.635 0.635)
			(layers "F.Cu" "F.Mask" "F.Paste")
			(net "P12V_MEZZ_B2")
		)
		(pad "138" smd circle
			(at 9.525 -3.175 90)
			(size 0.635 0.635)
			(layers "F.Cu" "F.Mask" "F.Paste")
			(net "CLK_100M_B2_N<0>")
		)
		(pad "139" smd circle
			(at 9.525 -1.905 90)
			(size 0.635 0.635)
			(layers "F.Cu" "F.Mask" "F.Paste")
			(net "GND")
		)
		(pad "140" smd circle
			(at 9.525 -0.635 90)
			(size 0.635 0.635)
			(layers "F.Cu" "F.Mask" "F.Paste")
			(net "CLK_100M_B2_N<1>")
		)
		(pad "141" smd circle
			(at 9.525 0.635 90)
			(size 0.635 0.635)
			(layers "F.Cu" "F.Mask" "F.Paste")
			(net "GND")
		)
		(pad "142" smd circle
			(at 9.525 1.905 90)
			(size 0.635 0.635)
			(layers "F.Cu" "F.Mask" "F.Paste")
			(net "CLK_100M_B2_N<2>")
		)
		(pad "143" smd circle
			(at 9.525 3.175 90)
			(size 0.635 0.635)
			(layers "F.Cu" "F.Mask" "F.Paste")
			(net "PCIE_RESET_B2_N<2>")
		)
		(pad "144" smd circle
			(at 9.525 4.445 90)
			(size 0.635 0.635)
			(layers "F.Cu" "F.Mask" "F.Paste")
			(net "CLK_100M_B2_N<3>")
		)
		(pad "145" smd circle
			(at 10.795 -4.445 90)
			(size 0.635 0.635)
			(layers "F.Cu" "F.Mask" "F.Paste")
			(net "P12V_MEZZ_B2")
		)
		(pad "146" smd circle
			(at 10.795 -3.175 90)
			(size 0.635 0.635)
			(layers "F.Cu" "F.Mask" "F.Paste")
			(net "GND")
		)
		(pad "147" smd circle
			(at 10.795 -1.905 90)
			(size 0.635 0.635)
			(layers "F.Cu" "F.Mask" "F.Paste")
			(net "GND")
		)
		(pad "148" smd circle
			(at 10.795 -0.635 90)
			(size 0.635 0.635)
			(layers "F.Cu" "F.Mask" "F.Paste")
			(net "PCIE_CFG_B2_ID1")
		)
		(pad "149" smd circle
			(at 10.795 0.635 90)
			(size 0.635 0.635)
			(layers "F.Cu" "F.Mask" "F.Paste")
			(net "PCIE_CFG_B2_ID0")
		)
		(pad "150" smd circle
			(at 10.795 1.905 90)
			(size 0.635 0.635)
			(layers "F.Cu" "F.Mask" "F.Paste")
			(net "PCIE_RESET_B2_N<0>")
		)
		(pad "151" smd circle
			(at 10.795 3.175 90)
			(size 0.635 0.635)
			(layers "F.Cu" "F.Mask" "F.Paste")
			(net "PCIE_RESET_B2_N<1>")
		)
		(pad "152" smd circle
			(at 10.795 4.445 90)
			(size 0.635 0.635)
			(layers "F.Cu" "F.Mask" "F.Paste")
			(net "PCIE_RESET_B2_N<3>")
		)
		(pad "153" smd circle
			(at 12.065 -4.445 90)
			(size 0.635 0.635)
			(layers "F.Cu" "F.Mask" "F.Paste")
			(net "P12V_MEZZ_B2")
		)
		(pad "154" smd circle
			(at 12.065 -3.175 90)
			(size 0.635 0.635)
			(layers "F.Cu" "F.Mask" "F.Paste")
			(net "P12V_MEZZ_B2")
		)
		(pad "155" smd circle
			(at 12.065 -1.905 90)
			(size 0.635 0.635)
			(layers "F.Cu" "F.Mask" "F.Paste")
			(net "P12V_MEZZ_B2")
		)
		(pad "156" smd circle
			(at 12.065 -0.635 90)
			(size 0.635 0.635)
			(layers "F.Cu" "F.Mask" "F.Paste")
			(net "MEZZ_B2_SCL")
		)
		(pad "157" smd circle
			(at 12.065 0.635 90)
			(size 0.635 0.635)
			(layers "F.Cu" "F.Mask" "F.Paste")
			(net "MEZZ_B2_EN")
		)
		(pad "158" smd circle
			(at 12.065 1.905 90)
			(size 0.635 0.635)
			(layers "F.Cu" "F.Mask" "F.Paste")
			(net "MEZZ_B2_SDA")
		)
		(pad "159" smd circle
			(at 12.065 3.175 90)
			(size 0.635 0.635)
			(layers "F.Cu" "F.Mask" "F.Paste")
			(net "PCIE_WAKE_B2_N")
		)
		(pad "160" smd circle
			(at 12.065 4.445 90)
			(size 0.635 0.635)
			(layers "F.Cu" "F.Mask" "F.Paste")
			(net "MEZZ_PRESENT_B2_N")
		)
	)
)
